(kicad_pcb
	(version 20260206)
	(generator "pcbnew")
	(generator_version "10.0")
	(general
		(thickness 1.6)
		(legacy_teardrops no)
	)
	(paper "A4")
	(title_block
		(title "Bryce Canyon_SCC_16316-1_OCP.brd")
		(comment 1 "Bryce Canyon / footprints 460-466 of 1561")
	)
	(layers
		(0 "F.Cu" signal "TOP")
		(4 "In1.Cu" signal "L2GND")
		(6 "In2.Cu" signal "L3")
		(8 "In3.Cu" signal "L4VCC")
		(10 "In4.Cu" signal "L5VCC")
		(12 "In5.Cu" signal "L6")
		(14 "In6.Cu" signal "L7GND")
		(2 "B.Cu" signal "BOTTOM")
		(9 "F.Adhes" user "F.Adhesive")
		(11 "B.Adhes" user "B.Adhesive")
		(13 "F.Paste" user "Package Geometry/Pastemask Top")
		(15 "B.Paste" user "Package Geometry/Pastemask Bottom")
		(5 "F.SilkS" user "Ref Des/Silkscreen Top")
		(7 "B.SilkS" user "Ref Des/Silkscreen Bottom")
		(1 "F.Mask" user "Board Geometry/Soldermask Top")
		(3 "B.Mask" user "Board Geometry/Soldermask Bottom")
		(17 "Dwgs.User" user "User.Drawings")
		(19 "Cmts.User" user "User.Comments")
		(21 "Eco1.User" user "User.Eco1")
		(23 "Eco2.User" user "User.Eco2")
		(25 "Edge.Cuts" user "Board Geometry/Outline")
		(27 "Margin" user)
		(31 "F.CrtYd" user "Package Geometry/Place Bound Top")
		(29 "B.CrtYd" user "Package Geometry/Place Bound Bottom")
		(35 "F.Fab" user "Ref Des/Assembly Top")
		(33 "B.Fab" user "Ref Des/Assembly Bottom")
	)
	(footprint ""
		(layer "F.Cu")
		(at 64.008 -72.6948)
		(property "Reference" "R417"
			(at 0 0 0)
			(layer "F.SilkS")
			(hide yes)
			(effects
				(font
					(size 1.27 1.27)
				)
			)
		)
		(property "Value" "200KR2F-L-GP"
			(at 0.064008 -3.993896 0)
			(unlocked yes)
			(layer "F.Fab")
			(hide yes)
			(effects
				(font
					(size 1.016 1.016)
					(thickness 0.1524)
				)
			)
		)
		(property "Device Type" "R402H16"
			(at 0.064008 -5.517896 0)
			(unlocked yes)
			(layer "F.Fab")
			(hide yes)
			(effects
				(font
					(size 1.016 1.016)
					(thickness 0.1524)
				)
			)
		)
		(duplicate_pad_numbers_are_jumpers no)
		(fp_line
			(start -0.508 -0.9398)
			(end -0.508 0.9398)
			(stroke
				(width 0.1524)
				(type default)
			)
			(layer "F.SilkS")
		)
		(fp_line
			(start 0.508 -0.9398)
			(end -0.508 -0.9398)
			(stroke
				(width 0.1524)
				(type default)
			)
			(layer "F.SilkS")
		)
		(fp_rect
			(start -0.508 0.9398)
			(end 0.508 -0.9398)
			(stroke
				(width 0)
				(type default)
			)
			(fill no)
			(layer "F.CrtYd")
		)
		(fp_rect
			(start -0.508 0.9398)
			(end 0.508 -0.9398)
			(stroke
				(width 0)
				(type default)
			)
			(fill no)
			(layer "F.Fab")
		)
		(pad "1" smd custom
			(at 0 -0.4445)
			(size 0.1397 0.1397)
			(layers "F.Cu" "F.Mask" "F.Paste")
			(net "VREF5")
			(options
				(clearance outline)
				(anchor circle)
			)
			(primitives
				(gr_poly
					(pts
						(arc
							(start -0.1778 -0.2794)
							(mid -0.249642 -0.249642)
							(end -0.2794 -0.1778)
						)
						(arc
							(start -0.2794 0.1778)
							(mid -0.249642 0.249642)
							(end -0.1778 0.2794)
						)
						(arc
							(start 0.1778 0.2794)
							(mid 0.249642 0.249642)
							(end 0.2794 0.1778)
						)
						(arc
							(start 0.2794 -0.1778)
							(mid 0.249642 -0.249642)
							(end 0.1778 -0.2794)
						)
					)
					(width 0)
					(fill yes)
				)
			)
		)
		(pad "2" smd custom
			(at 0 0.4445)
			(size 0.1397 0.1397)
			(layers "F.Cu" "F.Mask" "F.Paste")
			(net "P3V3")
			(options
				(clearance outline)
				(anchor circle)
			)
			(primitives
				(gr_poly
					(pts
						(arc
							(start -0.1778 -0.2794)
							(mid -0.249642 -0.249642)
							(end -0.2794 -0.1778)
						)
						(arc
							(start -0.2794 0.1778)
							(mid -0.249642 0.249642)
							(end -0.1778 0.2794)
						)
						(arc
							(start 0.1778 0.2794)
							(mid 0.249642 0.249642)
							(end 0.2794 0.1778)
						)
						(arc
							(start 0.2794 -0.1778)
							(mid 0.249642 -0.249642)
							(end 0.1778 -0.2794)
						)
					)
					(width 0)
					(fill yes)
				)
			)
		)
	)
	(footprint ""
		(layer "F.Cu")
		(at 58.682128 -77.49667 180)
		(property "Reference" "U37"
			(at 0 0 180)
			(layer "F.SilkS")
			(hide yes)
			(effects
				(font
					(size 1.27 1.27)
				)
			)
		)
		(property "Value" "PCA9306DCTR-GP"
			(at 0 -11.6332 180)
			(unlocked yes)
			(layer "F.Fab")
			(hide yes)
			(effects
				(font
					(size 1.016 1.016)
					(thickness 0.1524)
				)
			)
		)
		(property "Device Type" "SSOIC8H52"
			(at 0 -13.1572 180)
			(unlocked yes)
			(layer "F.Fab")
			(hide yes)
			(effects
				(font
					(size 1.016 1.016)
					(thickness 0.1524)
				)
			)
		)
		(duplicate_pad_numbers_are_jumpers no)
		(fp_line
			(start 1.0668 0.5842)
			(end -1.524 0.5842)
			(stroke
				(width 0.1524)
				(type default)
			)
			(layer "F.SilkS")
		)
		(fp_line
			(start 1.0668 -0.5842)
			(end 1.0668 0.5842)
			(stroke
				(width 0.1524)
				(type default)
			)
			(layer "F.SilkS")
		)
		(fp_line
			(start -1.397 0)
			(end -1.7018 0.3048)
			(stroke
				(width 0.1524)
				(type default)
			)
			(layer "F.SilkS")
		)
		(fp_line
			(start -1.397 0)
			(end -1.7018 -0.3048)
			(stroke
				(width 0.1524)
				(type default)
			)
			(layer "F.SilkS")
		)
		(fp_line
			(start -1.524 0.5842)
			(end -1.524 2.286)
			(stroke
				(width 0.508)
				(type default)
			)
			(layer "F.SilkS")
		)
		(fp_line
			(start -1.7018 -0.5842)
			(end 1.0668 -0.5842)
			(stroke
				(width 0.1524)
				(type default)
			)
			(layer "F.SilkS")
		)
		(fp_line
			(start -1.7018 -0.5842)
			(end -1.7018 2.286)
			(stroke
				(width 0.1524)
				(type default)
			)
			(layer "F.SilkS")
		)
		(fp_poly
			(pts
				(xy -1.1684 -0.5842) (xy 1.0668 -0.5842) (xy 1.0668 0.5842) (xy -1.1684 0.5842)
			)
			(stroke
				(width 0)
				(type default)
			)
			(fill yes)
			(layer "F.SilkS")
		)
		(fp_poly
			(pts
				(xy -1.778 2.54) (xy 1.778 2.54) (xy 1.778 -2.54) (xy -1.778 -2.54)
			)
			(stroke
				(width 0)
				(type default)
			)
			(fill no)
			(layer "F.CrtYd")
		)
		(fp_poly
			(pts
				(xy -1.778 -2.54) (xy 1.778 -2.54) (xy 1.778 2.54) (xy -1.778 2.54)
			)
			(stroke
				(width 0)
				(type default)
			)
			(fill no)
			(layer "F.Fab")
		)
		(pad "1" smd rect
			(at -0.97536 1.6256 180)
			(size 0.3556 1.524)
			(layers "F.Cu" "F.Mask" "F.Paste")
			(net "GND")
		)
		(pad "2" smd rect
			(at -0.32512 1.6256 180)
			(size 0.3556 1.524)
			(layers "F.Cu" "F.Mask" "F.Paste")
			(net "P1V8_E")
		)
		(pad "3" smd rect
			(at 0.32512 1.6256 180)
			(size 0.3556 1.524)
			(layers "F.Cu" "F.Mask" "F.Paste")
			(net "I2C_DRIVE_PWR_SCL4_LS")
		)
		(pad "4" smd rect
			(at 0.97536 1.6256 180)
			(size 0.3556 1.524)
			(layers "F.Cu" "F.Mask" "F.Paste")
			(net "I2C_DRIVE_PWR_SDA4_LS")
		)
		(pad "5" smd rect
			(at 0.97536 -1.6256 180)
			(size 0.3556 1.524)
			(layers "F.Cu" "F.Mask" "F.Paste")
			(net "I2C_DRIVE_PWR_SDA4")
		)
		(pad "6" smd rect
			(at 0.32512 -1.6256 180)
			(size 0.3556 1.524)
			(layers "F.Cu" "F.Mask" "F.Paste")
			(net "I2C_DRIVE_PWR_SCL4")
		)
		(pad "7" smd rect
			(at -0.32512 -1.6256 180)
			(size 0.3556 1.524)
			(layers "F.Cu" "F.Mask" "F.Paste")
			(net "VREF4")
		)
		(pad "8" smd rect
			(at -0.97536 -1.6256 180)
			(size 0.3556 1.524)
			(layers "F.Cu" "F.Mask" "F.Paste")
			(net "LS_EN_U37")
		)
	)
	(footprint ""
		(layer "F.Cu")
		(at 12.319 -48.4378 -90)
		(property "Reference" "C574"
			(at 0 0 270)
			(layer "F.SilkS")
			(hide yes)
			(effects
				(font
					(size 1.27 1.27)
				)
			)
		)
		(property "Value" "SCD015U25V2KX-GP"
			(at 1.1811 -2.7051 270)
			(unlocked yes)
			(layer "F.Fab")
			(hide yes)
			(effects
				(font
					(size 1.016 1.016)
					(thickness 0.1524)
				)
			)
		)
		(property "Device Type" "C402H22"
			(at 1.1811 -4.2291 270)
			(unlocked yes)
			(layer "F.Fab")
			(hide yes)
			(effects
				(font
					(size 1.016 1.016)
					(thickness 0.1524)
				)
			)
		)
		(duplicate_pad_numbers_are_jumpers no)
		(fp_rect
			(start -0.4318 0.9525)
			(end 0.4318 -0.9525)
			(stroke
				(width 0)
				(type default)
			)
			(fill no)
			(layer "F.CrtYd")
		)
		(fp_rect
			(start -0.4318 0.9525)
			(end 0.4318 -0.9525)
			(stroke
				(width 0)
				(type default)
			)
			(fill no)
			(layer "F.Fab")
		)
		(pad "1" smd custom
			(at 0 -0.4445 270)
			(size 0.1524 0.1524)
			(layers "F.Cu" "F.Mask" "F.Paste")
			(net "MB0_HS_SENSE_P")
			(options
				(clearance outline)
				(anchor circle)
			)
			(primitives
				(gr_poly
					(pts
						(arc
							(start 0.3048 -0.2032)
							(mid 0.275042 -0.275042)
							(end 0.2032 -0.3048)
						)
						(arc
							(start -0.2032 -0.3048)
							(mid -0.275042 -0.275042)
							(end -0.3048 -0.2032)
						)
						(arc
							(start -0.3048 0.2032)
							(mid -0.275042 0.275042)
							(end -0.2032 0.3048)
						)
						(arc
							(start 0.2032 0.3048)
							(mid 0.275042 0.275042)
							(end 0.3048 0.2032)
						)
					)
					(width 0)
					(fill yes)
				)
			)
		)
		(pad "2" smd custom
			(at 0 0.4445 270)
			(size 0.1524 0.1524)
			(layers "F.Cu" "F.Mask" "F.Paste")
			(net "MB0_HS_SENSE_N")
			(options
				(clearance outline)
				(anchor circle)
			)
			(primitives
				(gr_poly
					(pts
						(arc
							(start 0.3048 -0.2032)
							(mid 0.275042 -0.275042)
							(end 0.2032 -0.3048)
						)
						(arc
							(start -0.2032 -0.3048)
							(mid -0.275042 -0.275042)
							(end -0.3048 -0.2032)
						)
						(arc
							(start -0.3048 0.2032)
							(mid -0.275042 0.275042)
							(end -0.2032 0.3048)
						)
						(arc
							(start 0.2032 0.3048)
							(mid 0.275042 0.275042)
							(end 0.3048 0.2032)
						)
					)
					(width 0)
					(fill yes)
				)
			)
		)
	)
	(footprint ""
		(layer "F.Cu")
		(at 142.57782 -60.525152 -90)
		(property "Reference" "C38"
			(at 0 0 270)
			(layer "F.SilkS")
			(hide yes)
			(effects
				(font
					(size 1.27 1.27)
				)
			)
		)
		(property "Value" "SCD01U16V1KX-GP"
			(at -2.8321 -1.7399 270)
			(unlocked yes)
			(layer "F.Fab")
			(hide yes)
			(effects
				(font
					(size 1.016 1.016)
					(thickness 0.1524)
				)
			)
		)
		(property "Device Type" "C0201H13"
			(at -2.8321 -3.2639 270)
			(unlocked yes)
			(layer "F.Fab")
			(hide yes)
			(effects
				(font
					(size 1.016 1.016)
					(thickness 0.1524)
				)
			)
		)
		(duplicate_pad_numbers_are_jumpers no)
		(fp_rect
			(start -0.2794 0.6477)
			(end 0.2794 -0.6477)
			(stroke
				(width 0)
				(type default)
			)
			(fill no)
			(layer "F.CrtYd")
		)
		(fp_rect
			(start -0.2794 0.6477)
			(end 0.2794 -0.6477)
			(stroke
				(width 0)
				(type default)
			)
			(fill no)
			(layer "F.Fab")
		)
		(pad "1" smd custom
			(at 0 -0.2794 270)
			(size 0.0762 0.0762)
			(layers "F.Cu" "F.Mask" "F.Paste")
			(net "PHY_IOC_TO_SCC_45_DN")
			(options
				(clearance outline)
				(anchor circle)
			)
			(primitives
				(gr_poly
					(pts
						(arc
							(start 0.1524 -0.127)
							(mid 0.137521 -0.162921)
							(end 0.1016 -0.1778)
						)
						(arc
							(start -0.1016 -0.1778)
							(mid -0.137521 -0.162921)
							(end -0.1524 -0.127)
						)
						(arc
							(start -0.1524 0.127)
							(mid -0.137521 0.162921)
							(end -0.1016 0.1778)
						)
						(arc
							(start 0.1016 0.1778)
							(mid 0.137521 0.162921)
							(end 0.1524 0.127)
						)
					)
					(width 0)
					(fill yes)
				)
			)
		)
		(pad "2" smd custom
			(at 0 0.2794 270)
			(size 0.0762 0.0762)
			(layers "F.Cu" "F.Mask" "F.Paste")
			(net "PHY_IOC_TO_SCC_C_45_DN")
			(options
				(clearance outline)
				(anchor circle)
			)
			(primitives
				(gr_poly
					(pts
						(arc
							(start 0.1524 -0.127)
							(mid 0.137521 -0.162921)
							(end 0.1016 -0.1778)
						)
						(arc
							(start -0.1016 -0.1778)
							(mid -0.137521 -0.162921)
							(end -0.1524 -0.127)
						)
						(arc
							(start -0.1524 0.127)
							(mid -0.137521 0.162921)
							(end -0.1016 0.1778)
						)
						(arc
							(start 0.1016 0.1778)
							(mid 0.137521 0.162921)
							(end 0.1524 0.127)
						)
					)
					(width 0)
					(fill yes)
				)
			)
		)
	)
	(footprint ""
		(layer "F.Cu")
		(at 22.715982 -30.934152)
		(property "Reference" "C565"
			(at 0 0 0)
			(layer "F.SilkS")
			(hide yes)
			(effects
				(font
					(size 1.27 1.27)
				)
			)
		)
		(property "Value" "SC10U16V5KX-7-GP-U"
			(at -0.0762 -6.1214 0)
			(unlocked yes)
			(layer "F.Fab")
			(hide yes)
			(effects
				(font
					(size 1.016 1.016)
					(thickness 0.1524)
				)
			)
		)
		(property "Device Type" "C805H58"
			(at -0.0762 -8.1534 0)
			(unlocked yes)
			(layer "F.Fab")
			(hide yes)
			(effects
				(font
					(size 1.016 1.016)
					(thickness 0.1524)
				)
			)
		)
		(duplicate_pad_numbers_are_jumpers no)
		(fp_line
			(start 0.635 0)
			(end -0.635 0)
			(stroke
				(width 0.508)
				(type default)
			)
			(layer "F.SilkS")
		)
		(fp_rect
			(start -0.9652 1.778)
			(end 0.9652 -1.778)
			(stroke
				(width 0)
				(type default)
			)
			(fill no)
			(layer "F.CrtYd")
		)
		(fp_poly
			(pts
				(xy -0.9652 -1.778) (xy 0.9652 -1.778) (xy 0.9652 1.778) (xy -0.9652 1.778)
			)
			(stroke
				(width 0)
				(type default)
			)
			(fill no)
			(layer "F.Fab")
		)
		(pad "1" smd rect
			(at 0 -0.9652)
			(size 1.397 1.143)
			(layers "F.Cu" "F.Mask" "F.Paste")
			(net "P12V_MAIN")
		)
		(pad "2" smd rect
			(at 0 0.9652)
			(size 1.397 1.143)
			(layers "F.Cu" "F.Mask" "F.Paste")
			(net "GND")
		)
	)
	(footprint ""
		(layer "F.Cu")
		(at 13.310616 -79.355188 -90)
		(property "Reference" "U27"
			(at 0 0 270)
			(layer "F.SilkS")
			(hide yes)
			(effects
				(font
					(size 1.27 1.27)
				)
			)
		)
		(property "Value" "CAT24C64WI-GT3-GP"
			(at -3.707384 -1.5367 270)
			(unlocked yes)
			(layer "F.Fab")
			(hide yes)
			(effects
				(font
					(size 1.016 1.016)
					(thickness 0.1524)
				)
			)
		)
		(property "Device Type" "SOIC8H69"
			(at -3.707384 -3.0607 270)
			(unlocked yes)
			(layer "F.Fab")
			(hide yes)
			(effects
				(font
					(size 1.016 1.016)
					(thickness 0.1524)
				)
			)
		)
		(duplicate_pad_numbers_are_jumpers no)
		(fp_line
			(start -2.6289 3.4417)
			(end -2.6289 1.4732)
			(stroke
				(width 0.381)
				(type default)
			)
			(layer "F.SilkS")
		)
		(fp_line
			(start -2.7432 1.4224)
			(end -2.6416 1.4224)
			(stroke
				(width 0.1524)
				(type default)
			)
			(layer "F.SilkS")
		)
		(fp_line
			(start -2.7432 1.4224)
			(end 2.1336 1.4224)
			(stroke
				(width 0.1524)
				(type default)
			)
			(layer "F.SilkS")
		)
		(fp_line
			(start 2.1336 1.4224)
			(end 2.1336 -1.4224)
			(stroke
				(width 0.1524)
				(type default)
			)
			(layer "F.SilkS")
		)
		(fp_line
			(start -2.1844 -0.0508)
			(end -2.7178 0.508)
			(stroke
				(width 0.1524)
				(type default)
			)
			(layer "F.SilkS")
		)
		(fp_line
			(start -2.7178 -0.508)
			(end -2.1844 -0.0508)
			(stroke
				(width 0.1524)
				(type default)
			)
			(layer "F.SilkS")
		)
		(fp_line
			(start -2.7432 -1.4224)
			(end -2.7432 1.4224)
			(stroke
				(width 0.1524)
				(type default)
			)
			(layer "F.SilkS")
		)
		(fp_line
			(start 2.1336 -1.4224)
			(end -2.7432 -1.4224)
			(stroke
				(width 0.1524)
				(type default)
			)
			(layer "F.SilkS")
		)
		(fp_poly
			(pts
				(xy -2.2098 -1.4224) (xy -2.2098 1.4224) (xy 2.2098 1.4224) (xy 2.2098 -1.4224)
			)
			(stroke
				(width 0)
				(type default)
			)
			(fill yes)
			(layer "F.SilkS")
		)
		(fp_rect
			(start -2.450084 2.999994)
			(end 2.450084 -2.999994)
			(stroke
				(width 0)
				(type default)
			)
			(fill no)
			(layer "F.CrtYd")
		)
		(fp_poly
			(pts
				(xy -2.8194 3.6322) (xy -2.8194 -3.6322) (xy 2.8194 -3.6322) (xy 2.8194 1.18364) (xy 2.450084 1.18364)
				(xy 2.450084 -2.999994) (xy -2.450084 -2.999994) (xy -2.450084 2.999994) (xy 2.450084 2.999994)
				(xy 2.450084 1.18618) (xy 2.8194 1.18618) (xy 2.8194 3.6322)
			)
			(stroke
				(width 0)
				(type default)
			)
			(fill no)
			(layer "F.CrtYd")
		)
		(fp_rect
			(start -2.8194 3.6322)
			(end 2.8194 -3.6322)
			(stroke
				(width 0)
				(type default)
			)
			(fill no)
			(layer "F.Fab")
		)
		(pad "1" smd rect
			(at -1.905 2.54 270)
			(size 0.635 1.651)
			(layers "F.Cu" "F.Mask" "F.Paste")
			(net "EXP_EEPROM_A0")
		)
		(pad "2" smd rect
			(at -0.635 2.54 270)
			(size 0.635 1.651)
			(layers "F.Cu" "F.Mask" "F.Paste")
			(net "EXP_EEPROM_A1")
		)
		(pad "3" smd rect
			(at 0.635 2.54 270)
			(size 0.635 1.651)
			(layers "F.Cu" "F.Mask" "F.Paste")
			(net "EXP_EEPROM_A2")
		)
		(pad "4" smd rect
			(at 1.905 2.54 270)
			(size 0.635 1.651)
			(layers "F.Cu" "F.Mask" "F.Paste")
			(net "GND")
		)
		(pad "5" smd rect
			(at 1.905 -2.54 270)
			(size 0.635 1.651)
			(layers "F.Cu" "F.Mask" "F.Paste")
			(net "EXP_EEPROM_SDA")
		)
		(pad "6" smd rect
			(at 0.635 -2.54 270)
			(size 0.635 1.651)
			(layers "F.Cu" "F.Mask" "F.Paste")
			(net "EXP_EEPROM_SCL")
		)
		(pad "7" smd rect
			(at -0.635 -2.54 270)
			(size 0.635 1.651)
			(layers "F.Cu" "F.Mask" "F.Paste")
			(net "EXP_EEPROM_WP")
		)
		(pad "8" smd rect
			(at -1.905 -2.54 270)
			(size 0.635 1.651)
			(layers "F.Cu" "F.Mask" "F.Paste")
			(net "P3V3")
		)
	)
	(footprint ""
		(layer "F.Cu")
		(at 124.6632 -108.59008)
		(property "Reference" "TP167"
			(at 0 0 0)
			(layer "F.SilkS")
			(hide yes)
			(effects
				(font
					(size 1.27 1.27)
				)
			)
		)
		(property "Value" "TPAD28-2-GP"
			(at -0.0127 -1.6637 0)
			(unlocked yes)
			(layer "F.Fab")
			(hide yes)
			(effects
				(font
					(size 1.016 1.016)
					(thickness 0.1524)
				)
			)
		)
		(property "Device Type" "TPAD28"
			(at -0.0127 -3.1877 0)
			(unlocked yes)
			(layer "F.Fab")
			(hide yes)
			(effects
				(font
					(size 1.016 1.016)
					(thickness 0.1524)
				)
			)
		)
		(duplicate_pad_numbers_are_jumpers no)
		(fp_poly
			(pts
				(arc
					(start 0.3556 0)
					(mid -0.3556 0)
					(end 0.3556 0)
				)
			)
			(stroke
				(width 0)
				(type default)
			)
			(fill no)
			(layer "F.CrtYd")
		)
		(fp_poly
			(pts
				(arc
					(start 0.6096 0)
					(mid -0.6096 0)
					(end 0.6096 0)
				)
			)
			(stroke
				(width 0)
				(type default)
			)
			(fill no)
			(layer "F.Fab")
		)
		(pad "1" smd circle
			(at 0 0)
			(size 0.7112 0.7112)
			(layers "F.Cu" "F.Mask" "F.Paste")
			(net "INT_D2_CONN1")
		)
	)
)
